(kicad_pcb
	(version 20260206)
	(generator "pcbnew")
	(generator_version "10.0")
	(general
		(thickness 1.6)
		(legacy_teardrops no)
	)
	(paper "A4")
	(title_block
		(title "12092022_DA0F0TFB6D0_F0T_FAN_BOARD_MP5048_D_brd_v02_OCP.brd")
		(comment 1 "Grand Teton / footprints 614-619 of 924")
	)
	(layers
		(0 "F.Cu" signal "TOP")
		(4 "In1.Cu" signal "GND")
		(6 "In2.Cu" signal "IN1")
		(8 "In3.Cu" signal "IN2")
		(10 "In4.Cu" signal "GND1")
		(2 "B.Cu" signal "BOTTOM")
		(9 "F.Adhes" user "F.Adhesive")
		(11 "B.Adhes" user "B.Adhesive")
		(13 "F.Paste" user "Package Geometry/Pastemask Top")
		(15 "B.Paste" user "Package Geometry/Pastemask Bottom")
		(5 "F.SilkS" user "Ref Des/Silkscreen Top")
		(7 "B.SilkS" user "Ref Des/Silkscreen Bottom")
		(1 "F.Mask" user "Board Geometry/Soldermask Top")
		(3 "B.Mask" user "Board Geometry/Soldermask Bottom")
		(17 "Dwgs.User" user "User.Drawings")
		(19 "Cmts.User" user "User.Comments")
		(21 "Eco1.User" user "User.Eco1")
		(23 "Eco2.User" user "User.Eco2")
		(25 "Edge.Cuts" user "Board Geometry/Outline")
		(27 "Margin" user)
		(31 "F.CrtYd" user "Package Geometry/Place Bound Top")
		(29 "B.CrtYd" user "Package Geometry/Place Bound Bottom")
		(35 "F.Fab" user "Ref Des/Assembly Top")
		(33 "B.Fab" user "Ref Des/Assembly Bottom")
	)
	(footprint ""
		(layer "F.Cu")
		(at 33.02 -208.308956 180)
		(property "Reference" "C2030"
			(at 0 0 180)
			(layer "F.SilkS")
			(hide yes)
			(effects
				(font
					(size 1.27 1.27)
				)
			)
		)
		(property "Value" ""
			(at 0 0 180)
			(layer "F.Fab")
			(effects
				(font
					(size 1.27 1.27)
				)
			)
		)
		(duplicate_pad_numbers_are_jumpers no)
		(fp_line
			(start 0.7874 0.4064)
			(end -0.7874 0.4064)
			(stroke
				(width 0.1524)
				(type default)
			)
			(layer "F.SilkS")
		)
		(fp_line
			(start 0.7874 -0.4064)
			(end 0.7874 0.4064)
			(stroke
				(width 0.1524)
				(type default)
			)
			(layer "F.SilkS")
		)
		(fp_line
			(start -0.7874 0.4064)
			(end -0.7874 -0.4064)
			(stroke
				(width 0.1524)
				(type default)
			)
			(layer "F.SilkS")
		)
		(fp_line
			(start -0.7874 -0.4064)
			(end 0.7874 -0.4064)
			(stroke
				(width 0.1524)
				(type default)
			)
			(layer "F.SilkS")
		)
		(fp_line
			(start 0.67945 0.3048)
			(end 0.120396 0.3048)
			(stroke
				(width 0.1)
				(type default)
			)
			(layer "F.Fab")
		)
		(fp_line
			(start 0.67945 -0.3048)
			(end 0.67945 0.3048)
			(stroke
				(width 0.1)
				(type default)
			)
			(layer "F.Fab")
		)
		(fp_line
			(start 0.12065 -0.2794)
			(end 0.12065 -0.3048)
			(stroke
				(width 0.1)
				(type default)
			)
			(layer "F.Fab")
		)
		(fp_line
			(start 0.12065 -0.3048)
			(end 0.67945 -0.3048)
			(stroke
				(width 0.1)
				(type default)
			)
			(layer "F.Fab")
		)
		(fp_line
			(start 0.120396 0.3048)
			(end 0.120396 0.2794)
			(stroke
				(width 0.1)
				(type default)
			)
			(layer "F.Fab")
		)
		(fp_line
			(start 0.120396 0.2794)
			(end -0.12065 0.2794)
			(stroke
				(width 0.1)
				(type default)
			)
			(layer "F.Fab")
		)
		(fp_line
			(start -0.12065 0.3048)
			(end -0.67945 0.3048)
			(stroke
				(width 0.1)
				(type default)
			)
			(layer "F.Fab")
		)
		(fp_line
			(start -0.12065 0.2794)
			(end -0.12065 0.3048)
			(stroke
				(width 0.1)
				(type default)
			)
			(layer "F.Fab")
		)
		(fp_line
			(start -0.12065 -0.2794)
			(end 0.12065 -0.2794)
			(stroke
				(width 0.1)
				(type default)
			)
			(layer "F.Fab")
		)
		(fp_line
			(start -0.12065 -0.305054)
			(end -0.12065 -0.2794)
			(stroke
				(width 0.1)
				(type default)
			)
			(layer "F.Fab")
		)
		(fp_line
			(start -0.67945 0.3048)
			(end -0.67945 -0.305054)
			(stroke
				(width 0.1)
				(type default)
			)
			(layer "F.Fab")
		)
		(fp_line
			(start -0.67945 -0.305054)
			(end -0.12065 -0.305054)
			(stroke
				(width 0.1)
				(type default)
			)
			(layer "F.Fab")
		)
		(pad "1" smd circle
			(at -0.40005 0 180)
			(size 0 0)
			(layers "F.Cu" "F.Mask" "F.Paste")
			(net "FAN_1_TACH_IL_R")
		)
		(pad "2" smd circle
			(at 0.40005 0 180)
			(size 0 0)
			(layers "F.Cu" "F.Mask" "F.Paste")
			(net "GND")
		)
	)
	(footprint ""
		(layer "F.Cu")
		(at 9.906 -170.053 180)
		(property "Reference" "U25"
			(at 2.00533 -1.016 90)
			(unlocked yes)
			(layer "F.SilkS")
			(effects
				(font
					(size 0.7874 0.5842)
					(thickness 0.1524)
				)
				(justify left)
			)
		)
		(property "Value" ""
			(at 0 0 180)
			(layer "F.Fab")
			(effects
				(font
					(size 1.27 1.27)
				)
			)
		)
		(duplicate_pad_numbers_are_jumpers no)
		(fp_line
			(start 1.3462 1.100074)
			(end -1.3462 1.100074)
			(stroke
				(width 0.1524)
				(type default)
			)
			(layer "F.SilkS")
		)
		(fp_line
			(start 1.3462 -1.100074)
			(end 1.3462 1.100074)
			(stroke
				(width 0.1524)
				(type default)
			)
			(layer "F.SilkS")
		)
		(fp_line
			(start 0.670052 -1.100074)
			(end 1.3462 -1.100074)
			(stroke
				(width 0.1524)
				(type default)
			)
			(layer "F.SilkS")
		)
		(fp_line
			(start 0 -0.381)
			(end 0.670052 -1.100074)
			(stroke
				(width 0.1524)
				(type default)
			)
			(layer "F.SilkS")
		)
		(fp_line
			(start -0.670052 -1.100074)
			(end 0 -0.381)
			(stroke
				(width 0.1524)
				(type default)
			)
			(layer "F.SilkS")
		)
		(fp_line
			(start -1.3462 1.100074)
			(end -1.3462 -1.100074)
			(stroke
				(width 0.1524)
				(type default)
			)
			(layer "F.SilkS")
		)
		(fp_line
			(start -1.3462 -1.100074)
			(end -0.670052 -1.100074)
			(stroke
				(width 0.1524)
				(type default)
			)
			(layer "F.SilkS")
		)
		(fp_poly
			(pts
				(xy -1.524 -0.649986) (xy -2.286 -1.030986) (xy -2.286 -0.268986)
			)
			(stroke
				(width 0)
				(type default)
			)
			(fill yes)
			(layer "F.SilkS")
		)
		(fp_line
			(start 1.100074 0.8001)
			(end 0.670052 0.8001)
			(stroke
				(width 0.1)
				(type default)
			)
			(layer "F.Fab")
		)
		(fp_line
			(start 1.100074 -0.8001)
			(end 1.100074 0.8001)
			(stroke
				(width 0.1)
				(type default)
			)
			(layer "F.Fab")
		)
		(fp_line
			(start 0.670052 1.100074)
			(end -0.670052 1.100074)
			(stroke
				(width 0.1)
				(type default)
			)
			(layer "F.Fab")
		)
		(fp_line
			(start 0.670052 0.8001)
			(end 0.670052 1.100074)
			(stroke
				(width 0.1)
				(type default)
			)
			(layer "F.Fab")
		)
		(fp_line
			(start 0.670052 -0.8001)
			(end 1.100074 -0.8001)
			(stroke
				(width 0.1)
				(type default)
			)
			(layer "F.Fab")
		)
		(fp_line
			(start 0.670052 -0.8001)
			(end 0.670052 0.8001)
			(stroke
				(width 0.1)
				(type default)
			)
			(layer "F.Fab")
		)
		(fp_line
			(start 0.670052 -1.100074)
			(end 0.670052 -0.8001)
			(stroke
				(width 0.1)
				(type default)
			)
			(layer "F.Fab")
		)
		(fp_line
			(start -0.670052 1.100074)
			(end -0.670052 0.8001)
			(stroke
				(width 0.1)
				(type default)
			)
			(layer "F.Fab")
		)
		(fp_line
			(start -0.670052 0.8001)
			(end -0.670052 -0.8001)
			(stroke
				(width 0.1)
				(type default)
			)
			(layer "F.Fab")
		)
		(fp_line
			(start -0.670052 0.8001)
			(end -1.100074 0.8001)
			(stroke
				(width 0.1)
				(type default)
			)
			(layer "F.Fab")
		)
		(fp_line
			(start -0.670052 -0.8001)
			(end -0.670052 -1.100074)
			(stroke
				(width 0.1)
				(type default)
			)
			(layer "F.Fab")
		)
		(fp_line
			(start -0.670052 -1.100074)
			(end 0.670052 -1.100074)
			(stroke
				(width 0.1)
				(type default)
			)
			(layer "F.Fab")
		)
		(fp_line
			(start -1.100074 0.8001)
			(end -1.100074 -0.8001)
			(stroke
				(width 0.1)
				(type default)
			)
			(layer "F.Fab")
		)
		(fp_line
			(start -1.100074 -0.8001)
			(end -0.670052 -0.8001)
			(stroke
				(width 0.1)
				(type default)
			)
			(layer "F.Fab")
		)
		(fp_poly
			(pts
				(xy -1.524 -0.649986) (xy -2.286 -1.030986) (xy -2.286 -0.268986)
			)
			(stroke
				(width 0)
				(type default)
			)
			(fill yes)
			(layer "F.Fab")
		)
		(pad "1" smd rect
			(at -0.94996 -0.649986 90)
			(size 0.4064 0.508)
			(layers "F.Cu" "F.Mask" "F.Paste")
			(net "FAN_4_PRESENT_N")
		)
		(pad "2" smd rect
			(at -0.94996 0 90)
			(size 0.4064 0.508)
			(layers "F.Cu" "F.Mask" "F.Paste")
			(net "GND")
		)
		(pad "3" smd rect
			(at -0.94996 0.649986 90)
			(size 0.4064 0.508)
			(layers "F.Cu" "F.Mask" "F.Paste")
			(net "FAN_5_PRESENT_N")
		)
		(pad "4" smd rect
			(at 0.94996 0.649986 90)
			(size 0.4064 0.508)
			(layers "F.Cu" "F.Mask" "F.Paste")
			(net "FAN_5_PRSNT_BUF_R_N")
		)
		(pad "5" smd rect
			(at 0.94996 0 90)
			(size 0.4064 0.508)
			(layers "F.Cu" "F.Mask" "F.Paste")
			(net "P3V3_AUX")
		)
		(pad "6" smd rect
			(at 0.94996 -0.649986 90)
			(size 0.4064 0.508)
			(layers "F.Cu" "F.Mask" "F.Paste")
			(net "FAN_4_PRSNT_BUF_R_N")
		)
	)
	(footprint ""
		(layer "F.Cu")
		(at 16.520922 -106.776012)
		(property "Reference" "C2033"
			(at 0 0 0)
			(layer "F.SilkS")
			(hide yes)
			(effects
				(font
					(size 1.27 1.27)
				)
			)
		)
		(property "Value" ""
			(at 0 0 0)
			(layer "F.Fab")
			(effects
				(font
					(size 1.27 1.27)
				)
			)
		)
		(duplicate_pad_numbers_are_jumpers no)
		(fp_line
			(start -0.7874 -0.4064)
			(end 0.7874 -0.4064)
			(stroke
				(width 0.1524)
				(type default)
			)
			(layer "F.SilkS")
		)
		(fp_line
			(start -0.7874 0.4064)
			(end -0.7874 -0.4064)
			(stroke
				(width 0.1524)
				(type default)
			)
			(layer "F.SilkS")
		)
		(fp_line
			(start 0.7874 -0.4064)
			(end 0.7874 0.4064)
			(stroke
				(width 0.1524)
				(type default)
			)
			(layer "F.SilkS")
		)
		(fp_line
			(start 0.7874 0.4064)
			(end -0.7874 0.4064)
			(stroke
				(width 0.1524)
				(type default)
			)
			(layer "F.SilkS")
		)
		(fp_line
			(start -0.67945 -0.305054)
			(end -0.12065 -0.305054)
			(stroke
				(width 0.1)
				(type default)
			)
			(layer "F.Fab")
		)
		(fp_line
			(start -0.67945 0.3048)
			(end -0.67945 -0.305054)
			(stroke
				(width 0.1)
				(type default)
			)
			(layer "F.Fab")
		)
		(fp_line
			(start -0.12065 -0.305054)
			(end -0.12065 -0.2794)
			(stroke
				(width 0.1)
				(type default)
			)
			(layer "F.Fab")
		)
		(fp_line
			(start -0.12065 -0.2794)
			(end 0.12065 -0.2794)
			(stroke
				(width 0.1)
				(type default)
			)
			(layer "F.Fab")
		)
		(fp_line
			(start -0.12065 0.2794)
			(end -0.12065 0.3048)
			(stroke
				(width 0.1)
				(type default)
			)
			(layer "F.Fab")
		)
		(fp_line
			(start -0.12065 0.3048)
			(end -0.67945 0.3048)
			(stroke
				(width 0.1)
				(type default)
			)
			(layer "F.Fab")
		)
		(fp_line
			(start 0.120396 0.2794)
			(end -0.12065 0.2794)
			(stroke
				(width 0.1)
				(type default)
			)
			(layer "F.Fab")
		)
		(fp_line
			(start 0.120396 0.3048)
			(end 0.120396 0.2794)
			(stroke
				(width 0.1)
				(type default)
			)
			(layer "F.Fab")
		)
		(fp_line
			(start 0.12065 -0.3048)
			(end 0.67945 -0.3048)
			(stroke
				(width 0.1)
				(type default)
			)
			(layer "F.Fab")
		)
		(fp_line
			(start 0.12065 -0.2794)
			(end 0.12065 -0.3048)
			(stroke
				(width 0.1)
				(type default)
			)
			(layer "F.Fab")
		)
		(fp_line
			(start 0.67945 -0.3048)
			(end 0.67945 0.3048)
			(stroke
				(width 0.1)
				(type default)
			)
			(layer "F.Fab")
		)
		(fp_line
			(start 0.67945 0.3048)
			(end 0.120396 0.3048)
			(stroke
				(width 0.1)
				(type default)
			)
			(layer "F.Fab")
		)
		(pad "1" smd circle
			(at -0.40005 0)
			(size 0 0)
			(layers "F.Cu" "F.Mask" "F.Paste")
			(net "FAN_5_PWM_IL_R")
		)
		(pad "2" smd circle
			(at 0.40005 0)
			(size 0 0)
			(layers "F.Cu" "F.Mask" "F.Paste")
			(net "GND")
		)
	)
	(footprint ""
		(layer "F.Cu")
		(at 14.361922 -106.776012)
		(property "Reference" "R5201"
			(at 0 0 0)
			(layer "F.SilkS")
			(hide yes)
			(effects
				(font
					(size 1.27 1.27)
				)
			)
		)
		(property "Value" ""
			(at 0 0 0)
			(layer "F.Fab")
			(effects
				(font
					(size 1.27 1.27)
				)
			)
		)
		(duplicate_pad_numbers_are_jumpers no)
		(fp_line
			(start -0.7874 -0.4064)
			(end 0.7874 -0.4064)
			(stroke
				(width 0.1524)
				(type default)
			)
			(layer "F.SilkS")
		)
		(fp_line
			(start -0.7874 0.4064)
			(end -0.7874 -0.4064)
			(stroke
				(width 0.1524)
				(type default)
			)
			(layer "F.SilkS")
		)
		(fp_line
			(start 0.7874 -0.4064)
			(end 0.7874 0.4064)
			(stroke
				(width 0.1524)
				(type default)
			)
			(layer "F.SilkS")
		)
		(fp_line
			(start 0.7874 0.4064)
			(end -0.7874 0.4064)
			(stroke
				(width 0.1524)
				(type default)
			)
			(layer "F.SilkS")
		)
		(fp_line
			(start -0.67945 -0.305054)
			(end -0.12065 -0.305054)
			(stroke
				(width 0.1)
				(type default)
			)
			(layer "F.Fab")
		)
		(fp_line
			(start -0.67945 0.3048)
			(end -0.67945 -0.305054)
			(stroke
				(width 0.1)
				(type default)
			)
			(layer "F.Fab")
		)
		(fp_line
			(start -0.12065 -0.305054)
			(end -0.12065 -0.2794)
			(stroke
				(width 0.1)
				(type default)
			)
			(layer "F.Fab")
		)
		(fp_line
			(start -0.12065 -0.2794)
			(end 0.12065 -0.2794)
			(stroke
				(width 0.1)
				(type default)
			)
			(layer "F.Fab")
		)
		(fp_line
			(start -0.12065 0.2794)
			(end -0.12065 0.3048)
			(stroke
				(width 0.1)
				(type default)
			)
			(layer "F.Fab")
		)
		(fp_line
			(start -0.12065 0.3048)
			(end -0.67945 0.3048)
			(stroke
				(width 0.1)
				(type default)
			)
			(layer "F.Fab")
		)
		(fp_line
			(start 0.120396 0.2794)
			(end -0.12065 0.2794)
			(stroke
				(width 0.1)
				(type default)
			)
			(layer "F.Fab")
		)
		(fp_line
			(start 0.120396 0.3048)
			(end 0.120396 0.2794)
			(stroke
				(width 0.1)
				(type default)
			)
			(layer "F.Fab")
		)
		(fp_line
			(start 0.12065 -0.3048)
			(end 0.67945 -0.3048)
			(stroke
				(width 0.1)
				(type default)
			)
			(layer "F.Fab")
		)
		(fp_line
			(start 0.12065 -0.2794)
			(end 0.12065 -0.3048)
			(stroke
				(width 0.1)
				(type default)
			)
			(layer "F.Fab")
		)
		(fp_line
			(start 0.67945 -0.3048)
			(end 0.67945 0.3048)
			(stroke
				(width 0.1)
				(type default)
			)
			(layer "F.Fab")
		)
		(fp_line
			(start 0.67945 0.3048)
			(end 0.120396 0.3048)
			(stroke
				(width 0.1)
				(type default)
			)
			(layer "F.Fab")
		)
		(pad "1" smd circle
			(at -0.40005 0)
			(size 0 0)
			(layers "F.Cu" "F.Mask" "F.Paste")
			(net "FAN_5_PWM_IL_R")
		)
		(pad "2" smd circle
			(at 0.40005 0)
			(size 0 0)
			(layers "F.Cu" "F.Mask" "F.Paste")
			(net "FAN_5_PWM_IL")
		)
	)
	(footprint ""
		(layer "F.Cu")
		(at 27.94 -135.382 -90)
		(property "Reference" "R5458"
			(at 0 0 270)
			(layer "F.SilkS")
			(hide yes)
			(effects
				(font
					(size 1.27 1.27)
				)
			)
		)
		(property "Value" ""
			(at 0 0 270)
			(layer "F.Fab")
			(effects
				(font
					(size 1.27 1.27)
				)
			)
		)
		(duplicate_pad_numbers_are_jumpers no)
		(fp_line
			(start -0.7874 0.4064)
			(end -0.7874 -0.4064)
			(stroke
				(width 0.1524)
				(type default)
			)
			(layer "F.SilkS")
		)
		(fp_line
			(start 0.7874 0.4064)
			(end -0.7874 0.4064)
			(stroke
				(width 0.1524)
				(type default)
			)
			(layer "F.SilkS")
		)
		(fp_line
			(start -0.7874 -0.4064)
			(end 0.7874 -0.4064)
			(stroke
				(width 0.1524)
				(type default)
			)
			(layer "F.SilkS")
		)
		(fp_line
			(start 0.7874 -0.4064)
			(end 0.7874 0.4064)
			(stroke
				(width 0.1524)
				(type default)
			)
			(layer "F.SilkS")
		)
		(fp_line
			(start -0.67945 0.3048)
			(end -0.67945 -0.305054)
			(stroke
				(width 0.1)
				(type default)
			)
			(layer "F.Fab")
		)
		(fp_line
			(start -0.12065 0.3048)
			(end -0.67945 0.3048)
			(stroke
				(width 0.1)
				(type default)
			)
			(layer "F.Fab")
		)
		(fp_line
			(start 0.120396 0.3048)
			(end 0.120396 0.2794)
			(stroke
				(width 0.1)
				(type default)
			)
			(layer "F.Fab")
		)
		(fp_line
			(start 0.67945 0.3048)
			(end 0.120396 0.3048)
			(stroke
				(width 0.1)
				(type default)
			)
			(layer "F.Fab")
		)
		(fp_line
			(start -0.12065 0.2794)
			(end -0.12065 0.3048)
			(stroke
				(width 0.1)
				(type default)
			)
			(layer "F.Fab")
		)
		(fp_line
			(start 0.120396 0.2794)
			(end -0.12065 0.2794)
			(stroke
				(width 0.1)
				(type default)
			)
			(layer "F.Fab")
		)
		(fp_line
			(start -0.12065 -0.2794)
			(end 0.12065 -0.2794)
			(stroke
				(width 0.1)
				(type default)
			)
			(layer "F.Fab")
		)
		(fp_line
			(start 0.12065 -0.2794)
			(end 0.12065 -0.3048)
			(stroke
				(width 0.1)
				(type default)
			)
			(layer "F.Fab")
		)
		(fp_line
			(start 0.12065 -0.3048)
			(end 0.67945 -0.3048)
			(stroke
				(width 0.1)
				(type default)
			)
			(layer "F.Fab")
		)
		(fp_line
			(start 0.67945 -0.3048)
			(end 0.67945 0.3048)
			(stroke
				(width 0.1)
				(type default)
			)
			(layer "F.Fab")
		)
		(fp_line
			(start -0.67945 -0.305054)
			(end -0.12065 -0.305054)
			(stroke
				(width 0.1)
				(type default)
			)
			(layer "F.Fab")
		)
		(fp_line
			(start -0.12065 -0.305054)
			(end -0.12065 -0.2794)
			(stroke
				(width 0.1)
				(type default)
			)
			(layer "F.Fab")
		)
		(pad "1" smd circle
			(at -0.40005 0 270)
			(size 0 0)
			(layers "F.Cu" "F.Mask" "F.Paste")
			(net "SMB_PDBV_FAN_SDA")
		)
		(pad "2" smd circle
			(at 0.40005 0 270)
			(size 0 0)
			(layers "F.Cu" "F.Mask" "F.Paste")
			(net "SMB_PDBV_FAN_R_U317_SDA")
		)
	)
	(footprint ""
		(layer "F.Cu")
		(at 29.718 -143.891 -90)
		(property "Reference" "R4787"
			(at 0 0 270)
			(layer "F.SilkS")
			(hide yes)
			(effects
				(font
					(size 1.27 1.27)
				)
			)
		)
		(property "Value" ""
			(at 0 0 270)
			(layer "F.Fab")
			(effects
				(font
					(size 1.27 1.27)
				)
			)
		)
		(duplicate_pad_numbers_are_jumpers no)
		(fp_line
			(start -0.7874 0.4064)
			(end -0.7874 -0.4064)
			(stroke
				(width 0.1524)
				(type default)
			)
			(layer "F.SilkS")
		)
		(fp_line
			(start 0.7874 0.4064)
			(end -0.7874 0.4064)
			(stroke
				(width 0.1524)
				(type default)
			)
			(layer "F.SilkS")
		)
		(fp_line
			(start -0.7874 -0.4064)
			(end 0.7874 -0.4064)
			(stroke
				(width 0.1524)
				(type default)
			)
			(layer "F.SilkS")
		)
		(fp_line
			(start 0.7874 -0.4064)
			(end 0.7874 0.4064)
			(stroke
				(width 0.1524)
				(type default)
			)
			(layer "F.SilkS")
		)
		(fp_line
			(start -0.67945 0.3048)
			(end -0.67945 -0.305054)
			(stroke
				(width 0.1)
				(type default)
			)
			(layer "F.Fab")
		)
		(fp_line
			(start -0.12065 0.3048)
			(end -0.67945 0.3048)
			(stroke
				(width 0.1)
				(type default)
			)
			(layer "F.Fab")
		)
		(fp_line
			(start 0.120396 0.3048)
			(end 0.120396 0.2794)
			(stroke
				(width 0.1)
				(type default)
			)
			(layer "F.Fab")
		)
		(fp_line
			(start 0.67945 0.3048)
			(end 0.120396 0.3048)
			(stroke
				(width 0.1)
				(type default)
			)
			(layer "F.Fab")
		)
		(fp_line
			(start -0.12065 0.2794)
			(end -0.12065 0.3048)
			(stroke
				(width 0.1)
				(type default)
			)
			(layer "F.Fab")
		)
		(fp_line
			(start 0.120396 0.2794)
			(end -0.12065 0.2794)
			(stroke
				(width 0.1)
				(type default)
			)
			(layer "F.Fab")
		)
		(fp_line
			(start -0.12065 -0.2794)
			(end 0.12065 -0.2794)
			(stroke
				(width 0.1)
				(type default)
			)
			(layer "F.Fab")
		)
		(fp_line
			(start 0.12065 -0.2794)
			(end 0.12065 -0.3048)
			(stroke
				(width 0.1)
				(type default)
			)
			(layer "F.Fab")
		)
		(fp_line
			(start 0.12065 -0.3048)
			(end 0.67945 -0.3048)
			(stroke
				(width 0.1)
				(type default)
			)
			(layer "F.Fab")
		)
		(fp_line
			(start 0.67945 -0.3048)
			(end 0.67945 0.3048)
			(stroke
				(width 0.1)
				(type default)
			)
			(layer "F.Fab")
		)
		(fp_line
			(start -0.67945 -0.305054)
			(end -0.12065 -0.305054)
			(stroke
				(width 0.1)
				(type default)
			)
			(layer "F.Fab")
		)
		(fp_line
			(start -0.12065 -0.305054)
			(end -0.12065 -0.2794)
			(stroke
				(width 0.1)
				(type default)
			)
			(layer "F.Fab")
		)
		(pad "1" smd circle
			(at -0.40005 0 270)
			(size 0 0)
			(layers "F.Cu" "F.Mask" "F.Paste")
			(net "SMB_FAN2_R_SDA")
		)
		(pad "2" smd circle
			(at 0.40005 0 270)
			(size 0 0)
			(layers "F.Cu" "F.Mask" "F.Paste")
			(net "SMB_FAN2_SDA")
		)
	)
)
